# T6G (Grand Teton) — schematic netlist excerpt (pin names and nets, part order shuffled) for the footprints in the layout excerpt that follows; sources: Cadence DE-HDL packaged netlist, KiCad conversion of 04192023_DAF0TMB3IC0_F0TG_MB_C_brd_V02_OCP.brd

R8017  Q_RES  0 5% EMPTY  pkg 0402LF  page 167 : A = P3V3_AUX ; B = U124_VCC
BT2  CONN2_AAABAT029Y19  CONN2_AAA-BAT-029-Y19 IO  pkg BATTERY_AAA-BAT-029-Y19  page 187 : \1\ = P3V_BAT ; \2\ = GND

(kicad_pcb
	(version 20260206)
	(generator "pcbnew")
	(generator_version "10.0")
	(general
		(thickness 1.6)
		(legacy_teardrops no)
	)
	(paper "A4")
	(title_block
		(title "04192023_DAF0TMB3IC0_F0TG_MB_C_brd_V02_OCP.brd")
		(comment 1 "Grand Teton / footprints 4895-4896 of 8354")
	)
	(layers
		(0 "F.Cu" signal "TOP")
		(4 "In1.Cu" signal "GND")
		(6 "In2.Cu" signal "IN1")
		(8 "In3.Cu" signal "GND1")
		(10 "In4.Cu" signal "IN2")
		(12 "In5.Cu" signal "GND2")
		(14 "In6.Cu" signal "IN3")
		(16 "In7.Cu" signal "GND3")
		(18 "In8.Cu" signal "VCC")
		(20 "In9.Cu" signal "VCC1")
		(22 "In10.Cu" signal "GND4")
		(24 "In11.Cu" signal "IN4")
		(26 "In12.Cu" signal "GND5")
		(28 "In13.Cu" signal "IN5")
		(30 "In14.Cu" signal "GND6")
		(32 "In15.Cu" signal "IN6")
		(34 "In16.Cu" signal "GND7")
		(2 "B.Cu" signal "BOTTOM")
		(9 "F.Adhes" user "F.Adhesive")
		(11 "B.Adhes" user "B.Adhesive")
		(13 "F.Paste" user "Package Geometry/Pastemask Top")
		(15 "B.Paste" user "Package Geometry/Pastemask Bottom")
		(5 "F.SilkS" user "Ref Des/Silkscreen Top")
		(7 "B.SilkS" user "Ref Des/Silkscreen Bottom")
		(1 "F.Mask" user "Board Geometry/Soldermask Top")
		(3 "B.Mask" user "Board Geometry/Soldermask Bottom")
		(17 "Dwgs.User" user "User.Drawings")
		(19 "Cmts.User" user "User.Comments")
		(21 "Eco1.User" user "User.Eco1")
		(23 "Eco2.User" user "User.Eco2")
		(25 "Edge.Cuts" user "Board Geometry/Outline")
		(27 "Margin" user)
		(31 "F.CrtYd" user "Package Geometry/Place Bound Top")
		(29 "B.CrtYd" user "Package Geometry/Place Bound Bottom")
		(35 "F.Fab" user "Ref Des/Assembly Top")
		(33 "B.Fab" user "Ref Des/Assembly Bottom")
	)
	(footprint ""
		(layer "F.Cu")
		(at 293.720012 -34.001964 -90)
		(property "Reference" "BT2"
			(at 5.553964 1.243076 0)
			(unlocked yes)
			(layer "F.SilkS")
			(effects
				(font
					(size 0.7874 0.5842)
					(thickness 0.1524)
				)
				(justify left)
			)
		)
		(property "Value" ""
			(at 0 0 270)
			(layer "F.Fab")
			(effects
				(font
					(size 1.27 1.27)
				)
			)
		)
		(duplicate_pad_numbers_are_jumpers no)
		(fp_line
			(start 3.666236 22.820122)
			(end -3.666236 22.820122)
			(stroke
				(width 0.1524)
				(type default)
			)
			(layer "F.SilkS")
		)
		(fp_line
			(start -4.012692 22.800056)
			(end -3.724148 22.800056)
			(stroke
				(width 0.1524)
				(type default)
			)
			(layer "F.SilkS")
		)
		(fp_line
			(start 3.724148 22.800056)
			(end 4.012692 22.800056)
			(stroke
				(width 0.1524)
				(type default)
			)
			(layer "F.SilkS")
		)
		(fp_line
			(start -3.800094 1.807464)
			(end -3.800094 -1.180084)
			(stroke
				(width 0.1524)
				(type default)
			)
			(layer "F.SilkS")
		)
		(fp_line
			(start 3.899916 1.737614)
			(end 3.899916 -1.260094)
			(stroke
				(width 0.1524)
				(type default)
			)
			(layer "F.SilkS")
		)
		(fp_line
			(start -3.800094 -1.180084)
			(end 3.800094 -1.180084)
			(stroke
				(width 0.1524)
				(type default)
			)
			(layer "F.SilkS")
		)
		(fp_line
			(start 3.800094 -1.180084)
			(end 3.800094 1.807464)
			(stroke
				(width 0.1524)
				(type default)
			)
			(layer "F.SilkS")
		)
		(fp_line
			(start -3.899916 -1.260094)
			(end -3.899916 1.737614)
			(stroke
				(width 0.1524)
				(type default)
			)
			(layer "F.SilkS")
		)
		(fp_line
			(start 3.899916 -1.260094)
			(end -3.899916 -1.260094)
			(stroke
				(width 0.1524)
				(type default)
			)
			(layer "F.SilkS")
		)
		(fp_arc
			(start -3.666236 22.820122)
			(mid -11.149833 12.361061)
			(end -3.800094 1.807464)
			(stroke
				(width 0.1524)
				(type default)
			)
			(layer "F.SilkS")
		)
		(fp_arc
			(start -4.012692 22.800056)
			(mid -11.249872 12.229778)
			(end -3.899916 1.737614)
			(stroke
				(width 0.1524)
				(type default)
			)
			(layer "F.SilkS")
		)
		(fp_arc
			(start 3.800094 1.807464)
			(mid 11.149895 12.361062)
			(end 3.666236 22.820122)
			(stroke
				(width 0.1524)
				(type default)
			)
			(layer "F.SilkS")
		)
		(fp_arc
			(start 3.899916 1.737614)
			(mid 11.249813 12.229779)
			(end 4.012692 22.800056)
			(stroke
				(width 0.1524)
				(type default)
			)
			(layer "F.SilkS")
		)
		(fp_line
			(start 3.666236 22.820122)
			(end -3.666236 22.820122)
			(stroke
				(width 0.1)
				(type default)
			)
			(layer "F.Fab")
		)
		(fp_line
			(start -3.800094 1.807464)
			(end -3.800094 -1.180084)
			(stroke
				(width 0.1)
				(type default)
			)
			(layer "F.Fab")
		)
		(fp_line
			(start -3.800094 -1.180084)
			(end 3.800094 -1.180084)
			(stroke
				(width 0.1)
				(type default)
			)
			(layer "F.Fab")
		)
		(fp_line
			(start 3.800094 -1.180084)
			(end 3.800094 1.807464)
			(stroke
				(width 0.1)
				(type default)
			)
			(layer "F.Fab")
		)
		(fp_arc
			(start -3.666236 22.820122)
			(mid -11.149833 12.361061)
			(end -3.800094 1.807464)
			(stroke
				(width 0.1)
				(type default)
			)
			(layer "F.Fab")
		)
		(fp_arc
			(start 3.800094 1.807464)
			(mid 11.149895 12.361062)
			(end 3.666236 22.820122)
			(stroke
				(width 0.1)
				(type default)
			)
			(layer "F.Fab")
		)
		(fp_text user "-"
			(at 0.26035 22.7076 180)
			(unlocked yes)
			(layer "F.Fab")
			(effects
				(font
					(size 1.905 1.4224)
					(thickness 0.1524)
				)
				(justify left)
			)
		)
		(fp_text user "+"
			(at 0.20955 -2.5908 180)
			(unlocked yes)
			(layer "F.Fab")
			(effects
				(font
					(size 1.905 1.4224)
					(thickness 0.1524)
				)
				(justify left)
			)
		)
		(pad "1" thru_hole rect
			(at 0 0 270)
			(size 1.6256 1.6256)
			(drill 1.1176)
			(layers "*.Cu" "*.Mask")
			(remove_unused_layers no)
			(net "P3V_BAT")
			(clearance 0)
			(padstack
				(mode front_inner_back)
				(layer "Inner"
					(shape circle)
					(size 1.6256 1.6256)
					(clearance 0)
				)
				(layer "B.Cu"
					(shape rect)
					(size 1.6256 1.6256)
					(clearance 0)
				)
			)
		)
		(pad "2" thru_hole circle
			(at 0 19.99996 270)
			(size 1.524 1.524)
			(drill 1.016)
			(layers "*.Cu" "*.Mask")
			(remove_unused_layers no)
			(net "GND")
			(clearance 0)
		)
	)
	(footprint ""
		(layer "F.Cu")
		(at 430.022 -58.42 -90)
		(property "Reference" "R8017"
			(at 0 0 270)
			(layer "F.SilkS")
			(hide yes)
			(effects
				(font
					(size 1.27 1.27)
				)
			)
		)
		(property "Value" ""
			(at 0 0 270)
			(layer "F.Fab")
			(effects
				(font
					(size 1.27 1.27)
				)
			)
		)
		(duplicate_pad_numbers_are_jumpers no)
		(fp_line
			(start -0.7874 0.4064)
			(end -0.7874 -0.4064)
			(stroke
				(width 0.1524)
				(type default)
			)
			(layer "F.SilkS")
		)
		(fp_line
			(start 0.7874 0.4064)
			(end -0.7874 0.4064)
			(stroke
				(width 0.1524)
				(type default)
			)
			(layer "F.SilkS")
		)
		(fp_line
			(start -0.7874 -0.4064)
			(end 0.7874 -0.4064)
			(stroke
				(width 0.1524)
				(type default)
			)
			(layer "F.SilkS")
		)
		(fp_line
			(start 0.7874 -0.4064)
			(end 0.7874 0.4064)
			(stroke
				(width 0.1524)
				(type default)
			)
			(layer "F.SilkS")
		)
		(fp_line
			(start -0.67945 0.3048)
			(end -0.67945 -0.305054)
			(stroke
				(width 0.1)
				(type default)
			)
			(layer "F.Fab")
		)
		(fp_line
			(start -0.12065 0.3048)
			(end -0.67945 0.3048)
			(stroke
				(width 0.1)
				(type default)
			)
			(layer "F.Fab")
		)
		(fp_line
			(start 0.120396 0.3048)
			(end 0.120396 0.2794)
			(stroke
				(width 0.1)
				(type default)
			)
			(layer "F.Fab")
		)
		(fp_line
			(start 0.67945 0.3048)
			(end 0.120396 0.3048)
			(stroke
				(width 0.1)
				(type default)
			)
			(layer "F.Fab")
		)
		(fp_line
			(start -0.12065 0.2794)
			(end -0.12065 0.3048)
			(stroke
				(width 0.1)
				(type default)
			)
			(layer "F.Fab")
		)
		(fp_line
			(start 0.120396 0.2794)
			(end -0.12065 0.2794)
			(stroke
				(width 0.1)
				(type default)
			)
			(layer "F.Fab")
		)
		(fp_line
			(start -0.12065 -0.2794)
			(end 0.12065 -0.2794)
			(stroke
				(width 0.1)
				(type default)
			)
			(layer "F.Fab")
		)
		(fp_line
			(start 0.12065 -0.2794)
			(end 0.12065 -0.3048)
			(stroke
				(width 0.1)
				(type default)
			)
			(layer "F.Fab")
		)
		(fp_line
			(start 0.12065 -0.3048)
			(end 0.67945 -0.3048)
			(stroke
				(width 0.1)
				(type default)
			)
			(layer "F.Fab")
		)
		(fp_line
			(start 0.67945 -0.3048)
			(end 0.67945 0.3048)
			(stroke
				(width 0.1)
				(type default)
			)
			(layer "F.Fab")
		)
		(fp_line
			(start -0.67945 -0.305054)
			(end -0.12065 -0.305054)
			(stroke
				(width 0.1)
				(type default)
			)
			(layer "F.Fab")
		)
		(fp_line
			(start -0.12065 -0.305054)
			(end -0.12065 -0.2794)
			(stroke
				(width 0.1)
				(type default)
			)
			(layer "F.Fab")
		)
		(pad "1" smd circle
			(at -0.40005 0 270)
			(size 0 0)
			(layers "F.Cu" "F.Mask" "F.Paste")
			(net "P3V3_AUX")
		)
		(pad "2" smd circle
			(at 0.40005 0 270)
			(size 0 0)
			(layers "F.Cu" "F.Mask" "F.Paste")
			(net "U124_VCC")
		)
	)
)
